#ISCELL
  pure_quanta quanta_title_block_c *
  *
#ISCELL
  standard tap *
  page28_i151
#ISCELL
  standard tap *
  page28_i152
#ISCELL
  standard tap *
  page28_i161
#ISCELL
  standard tap *
  page28_i165
#CELL
  pure_quanta socket4677_azif0045p001c01cs *
  page28_i169
#ISCELL
  standard tap *
  page28_i171
#ISCELL
  standard tap *
  page28_i173
#ISCELL
  standard tap *
  page28_i179
#ISCELL
  standard tap *
  page28_i184
#ISCELL
  standard tap *
  page28_i186
#ISCELL
  standard tap *
  page28_i188
#ISCELL
  standard offpage *
  page28_i281
#ISCELL
  standard offpage *
  page28_i282
#ISCELL
  standard offpage *
  page28_i286
#ISCELL
  standard offpage *
  page28_i287
#ISCELL
  standard tap *
  page28_i288
#ISCELL
  standard tap *
  page28_i289
#ISCELL
  standard tap *
  page28_i290
#ISCELL
  standard tap *
  page28_i292
#ISCELL
  standard tap *
  page28_i293
#ISCELL
  standard tap *
  page28_i294
#ISCELL
  standard tap *
  page28_i296
#ISCELL
  standard tap *
  page28_i297
#ISCELL
  standard tap *
  page28_i298
#ISCELL
  standard tap *
  page28_i299
#ISCELL
  standard tap *
  page28_i300
#ISCELL
  standard tap *
  page28_i301
#ISCELL
  standard tap *
  page28_i302
#ISCELL
  standard tap *
  page28_i303
#ISCELL
  standard tap *
  page28_i304
#ISCELL
  standard tap *
  page28_i305
#ISCELL
  standard tap *
  page28_i306
#ISCELL
  standard tap *
  page28_i307
#ISCELL
  standard tap *
  page28_i308
#ISCELL
  standard tap *
  page28_i309
#ISCELL
  standard tap *
  page28_i310
#ISCELL
  standard tap *
  page28_i311
